# T6G (Grand Teton) — schematic netlist excerpt (pin names and nets, part order shuffled) for the footprints in the layout excerpt that follows; sources: Cadence DE-HDL packaged netlist, KiCad conversion of 04192023_DAF0TMB3IC0_F0TG_MB_C_brd_V02_OCP.brd

C581  Q_CAP  1UF 4V 20% X6S  pkg 0201  page 279 : A = P0V9_CPU0_RT0_2A ; B = GND
C479  Q_CAP  100UF 4V 20% X6S  pkg C0805  page 356 : A = P0V9_CPU1_RT3_2A ; B = GND
R8109  Q_RES  10K 1% EMPTY  pkg 0402LF  page 267 : A = HSC_OC_VOL ; B = GND

(kicad_pcb
	(version 20260206)
	(generator "pcbnew")
	(generator_version "10.0")
	(general
		(thickness 1.6)
		(legacy_teardrops no)
	)
	(paper "A4")
	(title_block
		(title "04192023_DAF0TMB3IC0_F0TG_MB_C_brd_V02_OCP.brd")
		(comment 1 "Grand Teton / footprints 5038-5040 of 8354")
	)
	(layers
		(0 "F.Cu" signal "TOP")
		(4 "In1.Cu" signal "GND")
		(6 "In2.Cu" signal "IN1")
		(8 "In3.Cu" signal "GND1")
		(10 "In4.Cu" signal "IN2")
		(12 "In5.Cu" signal "GND2")
		(14 "In6.Cu" signal "IN3")
		(16 "In7.Cu" signal "GND3")
		(18 "In8.Cu" signal "VCC")
		(20 "In9.Cu" signal "VCC1")
		(22 "In10.Cu" signal "GND4")
		(24 "In11.Cu" signal "IN4")
		(26 "In12.Cu" signal "GND5")
		(28 "In13.Cu" signal "IN5")
		(30 "In14.Cu" signal "GND6")
		(32 "In15.Cu" signal "IN6")
		(34 "In16.Cu" signal "GND7")
		(2 "B.Cu" signal "BOTTOM")
		(9 "F.Adhes" user "F.Adhesive")
		(11 "B.Adhes" user "B.Adhesive")
		(13 "F.Paste" user "Package Geometry/Pastemask Top")
		(15 "B.Paste" user "Package Geometry/Pastemask Bottom")
		(5 "F.SilkS" user "Ref Des/Silkscreen Top")
		(7 "B.SilkS" user "Ref Des/Silkscreen Bottom")
		(1 "F.Mask" user "Board Geometry/Soldermask Top")
		(3 "B.Mask" user "Board Geometry/Soldermask Bottom")
		(17 "Dwgs.User" user "User.Drawings")
		(19 "Cmts.User" user "User.Comments")
		(21 "Eco1.User" user "User.Eco1")
		(23 "Eco2.User" user "User.Eco2")
		(25 "Edge.Cuts" user "Board Geometry/Outline")
		(27 "Margin" user)
		(31 "F.CrtYd" user "Package Geometry/Place Bound Top")
		(29 "B.CrtYd" user "Package Geometry/Place Bound Bottom")
		(35 "F.Fab" user "Ref Des/Assembly Top")
		(33 "B.Fab" user "Ref Des/Assembly Bottom")
	)
	(footprint ""
		(layer "B.Cu")
		(at 185.496708 -422.208452 90)
		(property "Reference" "R8109"
			(at 0 0 90)
			(layer "B.SilkS")
			(hide yes)
			(effects
				(font
					(size 1.27 1.27)
				)
				(justify mirror)
			)
		)
		(property "Value" ""
			(at 0 0 90)
			(layer "B.Fab")
			(effects
				(font
					(size 1.27 1.27)
				)
				(justify mirror)
			)
		)
		(duplicate_pad_numbers_are_jumpers no)
		(fp_line
			(start 0.7874 -0.4064)
			(end -0.7874 -0.4064)
			(stroke
				(width 0.1524)
				(type default)
			)
			(layer "B.SilkS")
		)
		(fp_line
			(start -0.7874 -0.4064)
			(end -0.7874 0.4064)
			(stroke
				(width 0.1524)
				(type default)
			)
			(layer "B.SilkS")
		)
		(fp_line
			(start 0.7874 0.4064)
			(end 0.7874 -0.4064)
			(stroke
				(width 0.1524)
				(type default)
			)
			(layer "B.SilkS")
		)
		(fp_line
			(start -0.7874 0.4064)
			(end 0.7874 0.4064)
			(stroke
				(width 0.1524)
				(type default)
			)
			(layer "B.SilkS")
		)
		(fp_line
			(start 0.67945 -0.305054)
			(end 0.12065 -0.305054)
			(stroke
				(width 0.1)
				(type default)
			)
			(layer "B.Fab")
		)
		(fp_line
			(start 0.12065 -0.305054)
			(end 0.12065 -0.2794)
			(stroke
				(width 0.1)
				(type default)
			)
			(layer "B.Fab")
		)
		(fp_line
			(start -0.12065 -0.3048)
			(end -0.67945 -0.3048)
			(stroke
				(width 0.1)
				(type default)
			)
			(layer "B.Fab")
		)
		(fp_line
			(start -0.67945 -0.3048)
			(end -0.67945 0.3048)
			(stroke
				(width 0.1)
				(type default)
			)
			(layer "B.Fab")
		)
		(fp_line
			(start 0.12065 -0.2794)
			(end -0.12065 -0.2794)
			(stroke
				(width 0.1)
				(type default)
			)
			(layer "B.Fab")
		)
		(fp_line
			(start -0.12065 -0.2794)
			(end -0.12065 -0.3048)
			(stroke
				(width 0.1)
				(type default)
			)
			(layer "B.Fab")
		)
		(fp_line
			(start 0.12065 0.2794)
			(end 0.12065 0.3048)
			(stroke
				(width 0.1)
				(type default)
			)
			(layer "B.Fab")
		)
		(fp_line
			(start -0.120396 0.2794)
			(end 0.12065 0.2794)
			(stroke
				(width 0.1)
				(type default)
			)
			(layer "B.Fab")
		)
		(fp_line
			(start 0.67945 0.3048)
			(end 0.67945 -0.305054)
			(stroke
				(width 0.1)
				(type default)
			)
			(layer "B.Fab")
		)
		(fp_line
			(start 0.12065 0.3048)
			(end 0.67945 0.3048)
			(stroke
				(width 0.1)
				(type default)
			)
			(layer "B.Fab")
		)
		(fp_line
			(start -0.120396 0.3048)
			(end -0.120396 0.2794)
			(stroke
				(width 0.1)
				(type default)
			)
			(layer "B.Fab")
		)
		(fp_line
			(start -0.67945 0.3048)
			(end -0.120396 0.3048)
			(stroke
				(width 0.1)
				(type default)
			)
			(layer "B.Fab")
		)
		(pad "1" smd circle
			(at 0.40005 0 270)
			(size 0 0)
			(layers "B.Cu" "B.Mask" "B.Paste")
			(net "HSC_OC_VOL")
		)
		(pad "2" smd circle
			(at -0.40005 0 270)
			(size 0 0)
			(layers "B.Cu" "B.Mask" "B.Paste")
			(net "GND")
		)
	)
	(footprint ""
		(layer "B.Cu")
		(at 109.519466 -390.587484)
		(property "Reference" "C479"
			(at 0 0 0)
			(layer "B.SilkS")
			(hide yes)
			(effects
				(font
					(size 1.27 1.27)
				)
				(justify mirror)
			)
		)
		(property "Value" ""
			(at 0 0 0)
			(layer "B.Fab")
			(effects
				(font
					(size 1.27 1.27)
				)
				(justify mirror)
			)
		)
		(duplicate_pad_numbers_are_jumpers no)
		(fp_line
			(start -1.524 -0.762)
			(end -1.524 0.762)
			(stroke
				(width 0.1524)
				(type default)
			)
			(layer "B.SilkS")
		)
		(fp_line
			(start -1.524 0.762)
			(end 1.524 0.762)
			(stroke
				(width 0.1524)
				(type default)
			)
			(layer "B.SilkS")
		)
		(fp_line
			(start 1.524 -0.762)
			(end -1.524 -0.762)
			(stroke
				(width 0.1524)
				(type default)
			)
			(layer "B.SilkS")
		)
		(fp_line
			(start 1.524 0.762)
			(end 1.524 -0.762)
			(stroke
				(width 0.1524)
				(type default)
			)
			(layer "B.SilkS")
		)
		(fp_line
			(start -1.1049 -0.724916)
			(end 1.1049 -0.724916)
			(stroke
				(width 0.1)
				(type default)
			)
			(layer "B.Fab")
		)
		(fp_line
			(start -1.1049 0.724916)
			(end -1.1049 -0.724916)
			(stroke
				(width 0.1)
				(type default)
			)
			(layer "B.Fab")
		)
		(fp_line
			(start 1.1049 -0.724916)
			(end 1.1049 0.724916)
			(stroke
				(width 0.1)
				(type default)
			)
			(layer "B.Fab")
		)
		(fp_line
			(start 1.1049 0.724916)
			(end -1.1049 0.724916)
			(stroke
				(width 0.1)
				(type default)
			)
			(layer "B.Fab")
		)
		(pad "1" smd rect
			(at 0.889 0)
			(size 1.016 1.27)
			(layers "B.Cu" "B.Mask" "B.Paste")
			(net "P0V9_CPU1_RT3_2A")
		)
		(pad "2" smd rect
			(at -0.889 0)
			(size 1.016 1.27)
			(layers "B.Cu" "B.Mask" "B.Paste")
			(net "GND")
		)
	)
	(footprint ""
		(layer "B.Cu")
		(at 306.978304 -395.148562 90)
		(property "Reference" "C581"
			(at 0 0 90)
			(layer "B.SilkS")
			(hide yes)
			(effects
				(font
					(size 1.27 1.27)
				)
				(justify mirror)
			)
		)
		(property "Value" ""
			(at 0 0 90)
			(layer "B.Fab")
			(effects
				(font
					(size 1.27 1.27)
				)
				(justify mirror)
			)
		)
		(duplicate_pad_numbers_are_jumpers no)
		(fp_line
			(start 0.299974 -0.150114)
			(end -0.299974 -0.150114)
			(stroke
				(width 0.1)
				(type default)
			)
			(layer "B.Fab")
		)
		(fp_line
			(start -0.299974 -0.150114)
			(end -0.299974 0.150114)
			(stroke
				(width 0.1)
				(type default)
			)
			(layer "B.Fab")
		)
		(fp_line
			(start 0.299974 0.150114)
			(end 0.299974 -0.150114)
			(stroke
				(width 0.1)
				(type default)
			)
			(layer "B.Fab")
		)
		(fp_line
			(start -0.299974 0.150114)
			(end 0.299974 0.150114)
			(stroke
				(width 0.1)
				(type default)
			)
			(layer "B.Fab")
		)
		(pad "1" smd rect
			(at 0.2667 0 270)
			(size 0.3048 0.381)
			(layers "B.Cu" "B.Mask" "B.Paste")
			(net "P0V9_CPU0_RT0_2A")
		)
		(pad "2" smd rect
			(at -0.2667 0 270)
			(size 0.3048 0.381)
			(layers "B.Cu" "B.Mask" "B.Paste")
			(net "GND")
		)
	)
)
